# T6G (Grand Teton) — schematic netlist excerpt (pin names and nets, part order shuffled) for the footprints in the layout excerpt that follows; sources: Cadence DE-HDL packaged netlist, KiCad conversion of 04192023_DAF0TMB3IC0_F0TG_MB_C_brd_V02_OCP.brd

C2117  Q_CAP  22UF 4V 20% X6S  pkg C0402  page 74 : A = PVDDIO_P1 ; B = GND
L6000  Q_INDUCTOR  BLM21PG221SN1D IND  pkg SMLF  page 177 : \1\ = P3V3_AUX ; \2\ = P3V3_AUX_CPU0_USB_AVDD33
R6711  Q_RES  0 5% CHIP  pkg 0402LF  page 81 : A = RST_RT_CPU1_P0_RESET_R_N ; B = RST_RT_CPU1_P0_RESET_R2_N

(kicad_pcb
	(version 20260206)
	(generator "pcbnew")
	(generator_version "10.0")
	(general
		(thickness 1.6)
		(legacy_teardrops no)
	)
	(paper "A4")
	(title_block
		(title "04192023_DAF0TMB3IC0_F0TG_MB_C_brd_V02_OCP.brd")
		(comment 1 "Grand Teton / footprints 6569-6571 of 8354")
	)
	(layers
		(0 "F.Cu" signal "TOP")
		(4 "In1.Cu" signal "GND")
		(6 "In2.Cu" signal "IN1")
		(8 "In3.Cu" signal "GND1")
		(10 "In4.Cu" signal "IN2")
		(12 "In5.Cu" signal "GND2")
		(14 "In6.Cu" signal "IN3")
		(16 "In7.Cu" signal "GND3")
		(18 "In8.Cu" signal "VCC")
		(20 "In9.Cu" signal "VCC1")
		(22 "In10.Cu" signal "GND4")
		(24 "In11.Cu" signal "IN4")
		(26 "In12.Cu" signal "GND5")
		(28 "In13.Cu" signal "IN5")
		(30 "In14.Cu" signal "GND6")
		(32 "In15.Cu" signal "IN6")
		(34 "In16.Cu" signal "GND7")
		(2 "B.Cu" signal "BOTTOM")
		(9 "F.Adhes" user "F.Adhesive")
		(11 "B.Adhes" user "B.Adhesive")
		(13 "F.Paste" user "Package Geometry/Pastemask Top")
		(15 "B.Paste" user "Package Geometry/Pastemask Bottom")
		(5 "F.SilkS" user "Ref Des/Silkscreen Top")
		(7 "B.SilkS" user "Ref Des/Silkscreen Bottom")
		(1 "F.Mask" user "Board Geometry/Soldermask Top")
		(3 "B.Mask" user "Board Geometry/Soldermask Bottom")
		(17 "Dwgs.User" user "User.Drawings")
		(19 "Cmts.User" user "User.Comments")
		(21 "Eco1.User" user "User.Eco1")
		(23 "Eco2.User" user "User.Eco2")
		(25 "Edge.Cuts" user "Board Geometry/Outline")
		(27 "Margin" user)
		(31 "F.CrtYd" user "Package Geometry/Place Bound Top")
		(29 "B.CrtYd" user "Package Geometry/Place Bound Bottom")
		(35 "F.Fab" user "Ref Des/Assembly Top")
		(33 "B.Fab" user "Ref Des/Assembly Bottom")
	)
	(footprint ""
		(layer "B.Cu")
		(at 178.981608 -126.833376 90)
		(property "Reference" "R6711"
			(at 0 0 90)
			(layer "B.SilkS")
			(hide yes)
			(effects
				(font
					(size 1.27 1.27)
				)
				(justify mirror)
			)
		)
		(property "Value" ""
			(at 0 0 90)
			(layer "B.Fab")
			(effects
				(font
					(size 1.27 1.27)
				)
				(justify mirror)
			)
		)
		(duplicate_pad_numbers_are_jumpers no)
		(fp_line
			(start 0.7874 -0.4064)
			(end -0.7874 -0.4064)
			(stroke
				(width 0.1524)
				(type default)
			)
			(layer "B.SilkS")
		)
		(fp_line
			(start -0.7874 -0.4064)
			(end -0.7874 0.4064)
			(stroke
				(width 0.1524)
				(type default)
			)
			(layer "B.SilkS")
		)
		(fp_line
			(start 0.7874 0.4064)
			(end 0.7874 -0.4064)
			(stroke
				(width 0.1524)
				(type default)
			)
			(layer "B.SilkS")
		)
		(fp_line
			(start -0.7874 0.4064)
			(end 0.7874 0.4064)
			(stroke
				(width 0.1524)
				(type default)
			)
			(layer "B.SilkS")
		)
		(fp_line
			(start 0.67945 -0.305054)
			(end 0.12065 -0.305054)
			(stroke
				(width 0.1)
				(type default)
			)
			(layer "B.Fab")
		)
		(fp_line
			(start 0.12065 -0.305054)
			(end 0.12065 -0.2794)
			(stroke
				(width 0.1)
				(type default)
			)
			(layer "B.Fab")
		)
		(fp_line
			(start -0.12065 -0.3048)
			(end -0.67945 -0.3048)
			(stroke
				(width 0.1)
				(type default)
			)
			(layer "B.Fab")
		)
		(fp_line
			(start -0.67945 -0.3048)
			(end -0.67945 0.3048)
			(stroke
				(width 0.1)
				(type default)
			)
			(layer "B.Fab")
		)
		(fp_line
			(start 0.12065 -0.2794)
			(end -0.12065 -0.2794)
			(stroke
				(width 0.1)
				(type default)
			)
			(layer "B.Fab")
		)
		(fp_line
			(start -0.12065 -0.2794)
			(end -0.12065 -0.3048)
			(stroke
				(width 0.1)
				(type default)
			)
			(layer "B.Fab")
		)
		(fp_line
			(start 0.12065 0.2794)
			(end 0.12065 0.3048)
			(stroke
				(width 0.1)
				(type default)
			)
			(layer "B.Fab")
		)
		(fp_line
			(start -0.120396 0.2794)
			(end 0.12065 0.2794)
			(stroke
				(width 0.1)
				(type default)
			)
			(layer "B.Fab")
		)
		(fp_line
			(start 0.67945 0.3048)
			(end 0.67945 -0.305054)
			(stroke
				(width 0.1)
				(type default)
			)
			(layer "B.Fab")
		)
		(fp_line
			(start 0.12065 0.3048)
			(end 0.67945 0.3048)
			(stroke
				(width 0.1)
				(type default)
			)
			(layer "B.Fab")
		)
		(fp_line
			(start -0.120396 0.3048)
			(end -0.120396 0.2794)
			(stroke
				(width 0.1)
				(type default)
			)
			(layer "B.Fab")
		)
		(fp_line
			(start -0.67945 0.3048)
			(end -0.120396 0.3048)
			(stroke
				(width 0.1)
				(type default)
			)
			(layer "B.Fab")
		)
		(pad "1" smd circle
			(at 0.40005 0 270)
			(size 0 0)
			(layers "B.Cu" "B.Mask" "B.Paste")
			(net "RST_RT_CPU1_P0_RESET_R_N")
		)
		(pad "2" smd circle
			(at -0.40005 0 270)
			(size 0 0)
			(layers "B.Cu" "B.Mask" "B.Paste")
			(net "RST_RT_CPU1_P0_RESET_R2_N")
		)
	)
	(footprint ""
		(layer "B.Cu")
		(at 100.271834 -265.045952)
		(property "Reference" "C2117"
			(at 0 0 0)
			(layer "B.SilkS")
			(hide yes)
			(effects
				(font
					(size 1.27 1.27)
				)
				(justify mirror)
			)
		)
		(property "Value" ""
			(at 0 0 0)
			(layer "B.Fab")
			(effects
				(font
					(size 1.27 1.27)
				)
				(justify mirror)
			)
		)
		(duplicate_pad_numbers_are_jumpers no)
		(fp_line
			(start -0.7874 -0.4064)
			(end -0.7874 0.4064)
			(stroke
				(width 0.1524)
				(type default)
			)
			(layer "B.SilkS")
		)
		(fp_line
			(start -0.7874 0.4064)
			(end 0.7874 0.4064)
			(stroke
				(width 0.1524)
				(type default)
			)
			(layer "B.SilkS")
		)
		(fp_line
			(start 0.7874 -0.4064)
			(end -0.7874 -0.4064)
			(stroke
				(width 0.1524)
				(type default)
			)
			(layer "B.SilkS")
		)
		(fp_line
			(start 0.7874 0.4064)
			(end 0.7874 -0.4064)
			(stroke
				(width 0.1524)
				(type default)
			)
			(layer "B.SilkS")
		)
		(fp_line
			(start -0.67945 -0.3048)
			(end -0.67945 0.3048)
			(stroke
				(width 0.1)
				(type default)
			)
			(layer "B.Fab")
		)
		(fp_line
			(start -0.67945 0.3048)
			(end -0.120396 0.3048)
			(stroke
				(width 0.1)
				(type default)
			)
			(layer "B.Fab")
		)
		(fp_line
			(start -0.12065 -0.3048)
			(end -0.67945 -0.3048)
			(stroke
				(width 0.1)
				(type default)
			)
			(layer "B.Fab")
		)
		(fp_line
			(start -0.12065 -0.2794)
			(end -0.12065 -0.3048)
			(stroke
				(width 0.1)
				(type default)
			)
			(layer "B.Fab")
		)
		(fp_line
			(start -0.120396 0.2794)
			(end 0.12065 0.2794)
			(stroke
				(width 0.1)
				(type default)
			)
			(layer "B.Fab")
		)
		(fp_line
			(start -0.120396 0.3048)
			(end -0.120396 0.2794)
			(stroke
				(width 0.1)
				(type default)
			)
			(layer "B.Fab")
		)
		(fp_line
			(start 0.12065 -0.305054)
			(end 0.12065 -0.2794)
			(stroke
				(width 0.1)
				(type default)
			)
			(layer "B.Fab")
		)
		(fp_line
			(start 0.12065 -0.2794)
			(end -0.12065 -0.2794)
			(stroke
				(width 0.1)
				(type default)
			)
			(layer "B.Fab")
		)
		(fp_line
			(start 0.12065 0.2794)
			(end 0.12065 0.3048)
			(stroke
				(width 0.1)
				(type default)
			)
			(layer "B.Fab")
		)
		(fp_line
			(start 0.12065 0.3048)
			(end 0.67945 0.3048)
			(stroke
				(width 0.1)
				(type default)
			)
			(layer "B.Fab")
		)
		(fp_line
			(start 0.67945 -0.305054)
			(end 0.12065 -0.305054)
			(stroke
				(width 0.1)
				(type default)
			)
			(layer "B.Fab")
		)
		(fp_line
			(start 0.67945 0.3048)
			(end 0.67945 -0.305054)
			(stroke
				(width 0.1)
				(type default)
			)
			(layer "B.Fab")
		)
		(pad "1" smd circle
			(at 0.40005 0 180)
			(size 0 0)
			(layers "B.Cu" "B.Mask" "B.Paste")
			(net "PVDDIO_P1")
		)
		(pad "2" smd circle
			(at -0.40005 0 180)
			(size 0 0)
			(layers "B.Cu" "B.Mask" "B.Paste")
			(net "GND")
		)
	)
	(footprint ""
		(layer "B.Cu")
		(at 141.53388 -33.475422)
		(property "Reference" "L6000"
			(at 0 0 0)
			(layer "B.SilkS")
			(hide yes)
			(effects
				(font
					(size 1.27 1.27)
				)
				(justify mirror)
			)
		)
		(property "Value" ""
			(at 0 0 0)
			(layer "B.Fab")
			(effects
				(font
					(size 1.27 1.27)
				)
				(justify mirror)
			)
		)
		(duplicate_pad_numbers_are_jumpers no)
		(fp_line
			(start -1.63576 -0.8128)
			(end -1.63576 0.8128)
			(stroke
				(width 0.1524)
				(type default)
			)
			(layer "B.SilkS")
		)
		(fp_line
			(start -1.63576 0.8128)
			(end 1.63576 0.8128)
			(stroke
				(width 0.1524)
				(type default)
			)
			(layer "B.SilkS")
		)
		(fp_line
			(start 1.63576 -0.8128)
			(end -1.63576 -0.8128)
			(stroke
				(width 0.1524)
				(type default)
			)
			(layer "B.SilkS")
		)
		(fp_line
			(start 1.63576 -0.8128)
			(end 1.63576 0.8128)
			(stroke
				(width 0.1524)
				(type default)
			)
			(layer "B.SilkS")
		)
		(fp_line
			(start -1.560576 -0.738632)
			(end 1.56083 -0.738632)
			(stroke
				(width 0.1)
				(type default)
			)
			(layer "B.Fab")
		)
		(fp_line
			(start -1.560576 0.7366)
			(end -1.560576 -0.738632)
			(stroke
				(width 0.1)
				(type default)
			)
			(layer "B.Fab")
		)
		(fp_line
			(start -1.524 0.7366)
			(end -1.560576 0.7366)
			(stroke
				(width 0.1)
				(type default)
			)
			(layer "B.Fab")
		)
		(fp_line
			(start 1.524 0.7366)
			(end -1.524 0.7366)
			(stroke
				(width 0.1)
				(type default)
			)
			(layer "B.Fab")
		)
		(fp_line
			(start 1.56083 -0.738632)
			(end 1.56083 0.7366)
			(stroke
				(width 0.1)
				(type default)
			)
			(layer "B.Fab")
		)
		(fp_line
			(start 1.56083 0.7366)
			(end 1.524 0.7366)
			(stroke
				(width 0.1)
				(type default)
			)
			(layer "B.Fab")
		)
		(pad "1" smd rect
			(at 0.94996 0)
			(size 1.1176 1.3716)
			(layers "B.Cu" "B.Mask" "B.Paste")
			(net "P3V3_AUX")
		)
		(pad "2" smd rect
			(at -0.94996 0)
			(size 1.1176 1.3716)
			(layers "B.Cu" "B.Mask" "B.Paste")
			(net "P3V3_AUX_CPU0_USB_AVDD33")
		)
	)
)
